(kicad_pcb
	(version 20260206)
	(generator "pcbnew")
	(generator_version "10.0")
	(general
		(thickness 1.6)
		(legacy_teardrops no)
	)
	(paper "A4")
	(title_block
		(title "Bryce Canyon_R.DPB_16317-1_OCP.brd")
		(comment 1 "Bryce Canyon / footprints 1084-1090 of 2099")
	)
	(layers
		(0 "F.Cu" signal "TOP")
		(4 "In1.Cu" signal "L2GND")
		(6 "In2.Cu" signal "L3")
		(8 "In3.Cu" signal "L4VCC")
		(10 "In4.Cu" signal "L5VCC")
		(12 "In5.Cu" signal "L6")
		(14 "In6.Cu" signal "L7GND")
		(2 "B.Cu" signal "BOTTOM")
		(9 "F.Adhes" user "F.Adhesive")
		(11 "B.Adhes" user "B.Adhesive")
		(13 "F.Paste" user "Package Geometry/Pastemask Top")
		(15 "B.Paste" user "Package Geometry/Pastemask Bottom")
		(5 "F.SilkS" user "Ref Des/Silkscreen Top")
		(7 "B.SilkS" user "Ref Des/Silkscreen Bottom")
		(1 "F.Mask" user "Board Geometry/Soldermask Top")
		(3 "B.Mask" user "Board Geometry/Soldermask Bottom")
		(17 "Dwgs.User" user "User.Drawings")
		(19 "Cmts.User" user "User.Comments")
		(21 "Eco1.User" user "User.Eco1")
		(23 "Eco2.User" user "User.Eco2")
		(25 "Edge.Cuts" user "Board Geometry/Outline")
		(27 "Margin" user)
		(31 "F.CrtYd" user "Package Geometry/Place Bound Top")
		(29 "B.CrtYd" user "Package Geometry/Place Bound Bottom")
		(35 "F.Fab" user "Ref Des/Assembly Top")
		(33 "B.Fab" user "Ref Des/Assembly Bottom")
	)
	(footprint ""
		(layer "F.Cu")
		(at 129.67589 -362.745274 180)
		(property "Reference" "Q128"
			(at 0 0 180)
			(layer "F.SilkS")
			(hide yes)
			(effects
				(font
					(size 1.27 1.27)
				)
			)
		)
		(property "Value" "AO4407AL-GP"
			(at -3.707384 -1.5367 180)
			(unlocked yes)
			(layer "F.Fab")
			(hide yes)
			(effects
				(font
					(size 1.016 1.016)
					(thickness 0.1524)
				)
			)
		)
		(property "Device Type" "SOIC8H69"
			(at -3.707384 -3.0607 180)
			(unlocked yes)
			(layer "F.Fab")
			(hide yes)
			(effects
				(font
					(size 1.016 1.016)
					(thickness 0.1524)
				)
			)
		)
		(duplicate_pad_numbers_are_jumpers no)
		(fp_line
			(start 2.1336 1.4224)
			(end 2.1336 -1.4224)
			(stroke
				(width 0.1524)
				(type default)
			)
			(layer "F.SilkS")
		)
		(fp_line
			(start 2.1336 -1.4224)
			(end -2.7432 -1.4224)
			(stroke
				(width 0.1524)
				(type default)
			)
			(layer "F.SilkS")
		)
		(fp_line
			(start -2.1844 -0.0508)
			(end -2.7178 0.508)
			(stroke
				(width 0.1524)
				(type default)
			)
			(layer "F.SilkS")
		)
		(fp_line
			(start -2.6289 3.4417)
			(end -2.6289 1.4732)
			(stroke
				(width 0.381)
				(type default)
			)
			(layer "F.SilkS")
		)
		(fp_line
			(start -2.7178 -0.508)
			(end -2.1844 -0.0508)
			(stroke
				(width 0.1524)
				(type default)
			)
			(layer "F.SilkS")
		)
		(fp_line
			(start -2.7432 1.4224)
			(end 2.1336 1.4224)
			(stroke
				(width 0.1524)
				(type default)
			)
			(layer "F.SilkS")
		)
		(fp_line
			(start -2.7432 1.4224)
			(end -2.6416 1.4224)
			(stroke
				(width 0.1524)
				(type default)
			)
			(layer "F.SilkS")
		)
		(fp_line
			(start -2.7432 -1.4224)
			(end -2.7432 1.4224)
			(stroke
				(width 0.1524)
				(type default)
			)
			(layer "F.SilkS")
		)
		(fp_poly
			(pts
				(xy -2.2098 -1.4224) (xy -2.2098 1.4224) (xy 2.2098 1.4224) (xy 2.2098 -1.4224)
			)
			(stroke
				(width 0)
				(type default)
			)
			(fill yes)
			(layer "F.SilkS")
		)
		(fp_rect
			(start -2.450084 2.999994)
			(end 2.450084 -2.999994)
			(stroke
				(width 0)
				(type default)
			)
			(fill no)
			(layer "F.CrtYd")
		)
		(fp_poly
			(pts
				(xy -2.8194 3.6322) (xy -2.8194 -3.6322) (xy 2.8194 -3.6322) (xy 2.8194 1.18364) (xy 2.450084 1.18364)
				(xy 2.450084 -2.999994) (xy -2.450084 -2.999994) (xy -2.450084 2.999994) (xy 2.450084 2.999994)
				(xy 2.450084 1.18618) (xy 2.8194 1.18618) (xy 2.8194 3.6322)
			)
			(stroke
				(width 0)
				(type default)
			)
			(fill no)
			(layer "F.CrtYd")
		)
		(fp_rect
			(start -2.8194 3.6322)
			(end 2.8194 -3.6322)
			(stroke
				(width 0)
				(type default)
			)
			(fill no)
			(layer "F.Fab")
		)
		(pad "1" smd rect
			(at -1.905 2.54 180)
			(size 0.635 1.651)
			(layers "F.Cu" "F.Mask" "F.Paste")
			(net "P12V_IN")
		)
		(pad "2" smd rect
			(at -0.635 2.54 180)
			(size 0.635 1.651)
			(layers "F.Cu" "F.Mask" "F.Paste")
			(net "P12V_IN")
		)
		(pad "3" smd rect
			(at 0.635 2.54 180)
			(size 0.635 1.651)
			(layers "F.Cu" "F.Mask" "F.Paste")
			(net "P12V_IN")
		)
		(pad "4" smd rect
			(at 1.905 2.54 180)
			(size 0.635 1.651)
			(layers "F.Cu" "F.Mask" "F.Paste")
			(net "GATE_FAN1_R")
		)
		(pad "5" smd rect
			(at 1.905 -2.54 180)
			(size 0.635 1.651)
			(layers "F.Cu" "F.Mask" "F.Paste")
			(net "P12V_FAN1")
		)
		(pad "6" smd rect
			(at 0.635 -2.54 180)
			(size 0.635 1.651)
			(layers "F.Cu" "F.Mask" "F.Paste")
			(net "P12V_FAN1")
		)
		(pad "7" smd rect
			(at -0.635 -2.54 180)
			(size 0.635 1.651)
			(layers "F.Cu" "F.Mask" "F.Paste")
			(net "P12V_FAN1")
		)
		(pad "8" smd rect
			(at -1.905 -2.54 180)
			(size 0.635 1.651)
			(layers "F.Cu" "F.Mask" "F.Paste")
			(net "P12V_FAN1")
		)
	)
	(footprint ""
		(layer "F.Cu")
		(at 141.097 -145.796)
		(property "Reference" "Q72"
			(at 0 0 0)
			(layer "F.SilkS")
			(hide yes)
			(effects
				(font
					(size 1.27 1.27)
				)
			)
		)
		(property "Value" "AO4407AL-GP"
			(at -3.707384 -1.5367 0)
			(unlocked yes)
			(layer "F.Fab")
			(hide yes)
			(effects
				(font
					(size 1.016 1.016)
					(thickness 0.1524)
				)
			)
		)
		(property "Device Type" "SOIC8H69"
			(at -3.707384 -3.0607 0)
			(unlocked yes)
			(layer "F.Fab")
			(hide yes)
			(effects
				(font
					(size 1.016 1.016)
					(thickness 0.1524)
				)
			)
		)
		(duplicate_pad_numbers_are_jumpers no)
		(fp_line
			(start -2.7432 -1.4224)
			(end -2.7432 1.4224)
			(stroke
				(width 0.1524)
				(type default)
			)
			(layer "F.SilkS")
		)
		(fp_line
			(start -2.7432 1.4224)
			(end -2.6416 1.4224)
			(stroke
				(width 0.1524)
				(type default)
			)
			(layer "F.SilkS")
		)
		(fp_line
			(start -2.7432 1.4224)
			(end 2.1336 1.4224)
			(stroke
				(width 0.1524)
				(type default)
			)
			(layer "F.SilkS")
		)
		(fp_line
			(start -2.7178 -0.508)
			(end -2.1844 -0.0508)
			(stroke
				(width 0.1524)
				(type default)
			)
			(layer "F.SilkS")
		)
		(fp_line
			(start -2.6289 3.4417)
			(end -2.6289 1.4732)
			(stroke
				(width 0.381)
				(type default)
			)
			(layer "F.SilkS")
		)
		(fp_line
			(start -2.1844 -0.0508)
			(end -2.7178 0.508)
			(stroke
				(width 0.1524)
				(type default)
			)
			(layer "F.SilkS")
		)
		(fp_line
			(start 2.1336 -1.4224)
			(end -2.7432 -1.4224)
			(stroke
				(width 0.1524)
				(type default)
			)
			(layer "F.SilkS")
		)
		(fp_line
			(start 2.1336 1.4224)
			(end 2.1336 -1.4224)
			(stroke
				(width 0.1524)
				(type default)
			)
			(layer "F.SilkS")
		)
		(fp_poly
			(pts
				(xy -2.2098 -1.4224) (xy -2.2098 1.4224) (xy 2.2098 1.4224) (xy 2.2098 -1.4224)
			)
			(stroke
				(width 0)
				(type default)
			)
			(fill yes)
			(layer "F.SilkS")
		)
		(fp_rect
			(start -2.450084 2.999994)
			(end 2.450084 -2.999994)
			(stroke
				(width 0)
				(type default)
			)
			(fill no)
			(layer "F.CrtYd")
		)
		(fp_poly
			(pts
				(xy -2.8194 3.6322) (xy -2.8194 -3.6322) (xy 2.8194 -3.6322) (xy 2.8194 1.18364) (xy 2.450084 1.18364)
				(xy 2.450084 -2.999994) (xy -2.450084 -2.999994) (xy -2.450084 2.999994) (xy 2.450084 2.999994)
				(xy 2.450084 1.18618) (xy 2.8194 1.18618) (xy 2.8194 3.6322)
			)
			(stroke
				(width 0)
				(type default)
			)
			(fill no)
			(layer "F.CrtYd")
		)
		(fp_rect
			(start -2.8194 3.6322)
			(end 2.8194 -3.6322)
			(stroke
				(width 0)
				(type default)
			)
			(fill no)
			(layer "F.Fab")
		)
		(pad "1" smd rect
			(at -1.905 2.54)
			(size 0.635 1.651)
			(layers "F.Cu" "F.Mask" "F.Paste")
			(net "P12V_B")
		)
		(pad "2" smd rect
			(at -0.635 2.54)
			(size 0.635 1.651)
			(layers "F.Cu" "F.Mask" "F.Paste")
			(net "P12V_B")
		)
		(pad "3" smd rect
			(at 0.635 2.54)
			(size 0.635 1.651)
			(layers "F.Cu" "F.Mask" "F.Paste")
			(net "P12V_B")
		)
		(pad "4" smd rect
			(at 1.905 2.54)
			(size 0.635 1.651)
			(layers "F.Cu" "F.Mask" "F.Paste")
			(net "SW_HDD_N16")
		)
		(pad "5" smd rect
			(at 1.905 -2.54)
			(size 0.635 1.651)
			(layers "F.Cu" "F.Mask" "F.Paste")
			(net "P12V_HDD16")
		)
		(pad "6" smd rect
			(at 0.635 -2.54)
			(size 0.635 1.651)
			(layers "F.Cu" "F.Mask" "F.Paste")
			(net "P12V_HDD16")
		)
		(pad "7" smd rect
			(at -0.635 -2.54)
			(size 0.635 1.651)
			(layers "F.Cu" "F.Mask" "F.Paste")
			(net "P12V_HDD16")
		)
		(pad "8" smd rect
			(at -1.905 -2.54)
			(size 0.635 1.651)
			(layers "F.Cu" "F.Mask" "F.Paste")
			(net "P12V_HDD16")
		)
	)
	(footprint ""
		(layer "F.Cu")
		(at 35.306 -263.144 -90)
		(property "Reference" "R898"
			(at 0 0 270)
			(layer "F.SilkS")
			(hide yes)
			(effects
				(font
					(size 1.27 1.27)
				)
			)
		)
		(property "Value" "10KR2F-2-GP"
			(at 0.064008 -3.993896 270)
			(unlocked yes)
			(layer "F.Fab")
			(hide yes)
			(effects
				(font
					(size 1.016 1.016)
					(thickness 0.1524)
				)
			)
		)
		(property "Device Type" "R402H16"
			(at 0.064008 -5.517896 270)
			(unlocked yes)
			(layer "F.Fab")
			(hide yes)
			(effects
				(font
					(size 1.016 1.016)
					(thickness 0.1524)
				)
			)
		)
		(duplicate_pad_numbers_are_jumpers no)
		(fp_line
			(start -0.508 -0.9398)
			(end -0.508 0.9398)
			(stroke
				(width 0.1524)
				(type default)
			)
			(layer "F.SilkS")
		)
		(fp_line
			(start 0.508 -0.9398)
			(end -0.508 -0.9398)
			(stroke
				(width 0.1524)
				(type default)
			)
			(layer "F.SilkS")
		)
		(fp_rect
			(start -0.508 0.9398)
			(end 0.508 -0.9398)
			(stroke
				(width 0)
				(type default)
			)
			(fill no)
			(layer "F.CrtYd")
		)
		(fp_rect
			(start -0.508 0.9398)
			(end 0.508 -0.9398)
			(stroke
				(width 0)
				(type default)
			)
			(fill no)
			(layer "F.Fab")
		)
		(pad "1" smd custom
			(at 0 -0.4445 270)
			(size 0.1397 0.1397)
			(layers "F.Cu" "F.Mask" "F.Paste")
			(net "P3V3_STBY_B")
			(options
				(clearance outline)
				(anchor circle)
			)
			(primitives
				(gr_poly
					(pts
						(arc
							(start -0.1778 -0.2794)
							(mid -0.249642 -0.249642)
							(end -0.2794 -0.1778)
						)
						(arc
							(start -0.2794 0.1778)
							(mid -0.249642 0.249642)
							(end -0.1778 0.2794)
						)
						(arc
							(start 0.1778 0.2794)
							(mid 0.249642 0.249642)
							(end 0.2794 0.1778)
						)
						(arc
							(start 0.2794 -0.1778)
							(mid 0.249642 -0.249642)
							(end 0.1778 -0.2794)
						)
					)
					(width 0)
					(fill yes)
				)
			)
		)
		(pad "2" smd custom
			(at 0 0.4445 270)
			(size 0.1397 0.1397)
			(layers "F.Cu" "F.Mask" "F.Paste")
			(net "HDD_PRSNT_0")
			(options
				(clearance outline)
				(anchor circle)
			)
			(primitives
				(gr_poly
					(pts
						(arc
							(start -0.1778 -0.2794)
							(mid -0.249642 -0.249642)
							(end -0.2794 -0.1778)
						)
						(arc
							(start -0.2794 0.1778)
							(mid -0.249642 0.249642)
							(end -0.1778 0.2794)
						)
						(arc
							(start 0.1778 0.2794)
							(mid 0.249642 0.249642)
							(end 0.2794 0.1778)
						)
						(arc
							(start 0.2794 -0.1778)
							(mid 0.249642 -0.249642)
							(end 0.1778 -0.2794)
						)
					)
					(width 0)
					(fill yes)
				)
			)
		)
	)
	(footprint ""
		(layer "F.Cu")
		(at 24.257 -275.463 180)
		(property "Reference" "C504"
			(at 0 0 180)
			(layer "F.SilkS")
			(hide yes)
			(effects
				(font
					(size 1.27 1.27)
				)
			)
		)
		(property "Value" "SC1U25V3KX-GP"
			(at 0 -2.8194 180)
			(unlocked yes)
			(layer "F.Fab")
			(hide yes)
			(effects
				(font
					(size 1.016 1.016)
					(thickness 0.1524)
				)
			)
		)
		(property "Device Type" "C603H36"
			(at 0 -4.3434 180)
			(unlocked yes)
			(layer "F.Fab")
			(hide yes)
			(effects
				(font
					(size 1.016 1.016)
					(thickness 0.1524)
				)
			)
		)
		(duplicate_pad_numbers_are_jumpers no)
		(fp_line
			(start 0.508 0)
			(end -0.508 0)
			(stroke
				(width 0.2032)
				(type default)
			)
			(layer "F.SilkS")
		)
		(fp_rect
			(start -0.5842 1.3335)
			(end 0.5842 -1.3335)
			(stroke
				(width 0)
				(type default)
			)
			(fill no)
			(layer "F.CrtYd")
		)
		(fp_rect
			(start -0.5842 1.3335)
			(end 0.5842 -1.3335)
			(stroke
				(width 0)
				(type default)
			)
			(fill no)
			(layer "F.Fab")
		)
		(pad "1" smd custom
			(at 0 -0.762 180)
			(size 0.2159 0.2159)
			(layers "F.Cu" "F.Mask" "F.Paste")
			(net "P12V_HDD0")
			(options
				(clearance outline)
				(anchor circle)
			)
			(primitives
				(gr_poly
					(pts
						(arc
							(start -0.3302 -0.4318)
							(mid -0.402042 -0.402042)
							(end -0.4318 -0.3302)
						)
						(arc
							(start -0.4318 0.3302)
							(mid -0.402042 0.402042)
							(end -0.3302 0.4318)
						)
						(arc
							(start 0.3302 0.4318)
							(mid 0.402042 0.402042)
							(end 0.4318 0.3302)
						)
						(arc
							(start 0.4318 -0.3302)
							(mid 0.402042 -0.402042)
							(end 0.3302 -0.4318)
						)
					)
					(width 0)
					(fill yes)
				)
			)
		)
		(pad "2" smd custom
			(at 0 0.762 180)
			(size 0.2159 0.2159)
			(layers "F.Cu" "F.Mask" "F.Paste")
			(net "GND")
			(options
				(clearance outline)
				(anchor circle)
			)
			(primitives
				(gr_poly
					(pts
						(arc
							(start -0.3302 -0.4318)
							(mid -0.402042 -0.402042)
							(end -0.4318 -0.3302)
						)
						(arc
							(start -0.4318 0.3302)
							(mid -0.402042 0.402042)
							(end -0.3302 0.4318)
						)
						(arc
							(start 0.3302 0.4318)
							(mid 0.402042 0.402042)
							(end 0.4318 0.3302)
						)
						(arc
							(start 0.4318 -0.3302)
							(mid 0.402042 -0.402042)
							(end 0.3302 -0.4318)
						)
					)
					(width 0)
					(fill yes)
				)
			)
		)
	)
	(footprint ""
		(layer "F.Cu")
		(at 446.242186 -121.210578)
		(property "Reference" "TP205"
			(at 0 0 0)
			(layer "F.SilkS")
			(hide yes)
			(effects
				(font
					(size 1.27 1.27)
				)
			)
		)
		(property "Value" "*"
			(at -0.0508 -1.6764 0)
			(unlocked yes)
			(layer "F.Fab")
			(hide yes)
			(effects
				(font
					(size 1.016 1.016)
					(thickness 0.1524)
				)
			)
		)
		(property "Device Type" "TPAD32"
			(at -0.0508 -3.2004 0)
			(unlocked yes)
			(layer "F.Fab")
			(hide yes)
			(effects
				(font
					(size 1.016 1.016)
					(thickness 0.1524)
				)
			)
		)
		(duplicate_pad_numbers_are_jumpers no)
		(fp_poly
			(pts
				(arc
					(start 0.4064 0)
					(mid -0.4064 0)
					(end 0.4064 0)
				)
			)
			(stroke
				(width 0)
				(type default)
			)
			(fill no)
			(layer "F.CrtYd")
		)
		(fp_poly
			(pts
				(arc
					(start 0.7112 0)
					(mid -0.7112 0)
					(end 0.7112 0)
				)
			)
			(stroke
				(width 0)
				(type default)
			)
			(fill no)
			(layer "F.Fab")
		)
		(pad "1" smd circle
			(at 0 0)
			(size 0.8128 0.8128)
			(layers "F.Cu" "F.Mask" "F.Paste")
			(net "P5V_B_4_PGOOD")
		)
	)
	(footprint ""
		(layer "F.Cu")
		(at 469.773 -265.684 -90)
		(property "Reference" "C178"
			(at 0 0 270)
			(layer "F.SilkS")
			(hide yes)
			(effects
				(font
					(size 1.27 1.27)
				)
			)
		)
		(property "Value" "SC4D7U25V5KX-1-GP"
			(at -0.0762 -6.1214 270)
			(unlocked yes)
			(layer "F.Fab")
			(hide yes)
			(effects
				(font
					(size 1.016 1.016)
					(thickness 0.1524)
				)
			)
		)
		(property "Device Type" "C805H58"
			(at -0.0762 -8.1534 270)
			(unlocked yes)
			(layer "F.Fab")
			(hide yes)
			(effects
				(font
					(size 1.016 1.016)
					(thickness 0.1524)
				)
			)
		)
		(duplicate_pad_numbers_are_jumpers no)
		(fp_line
			(start 0.635 0)
			(end -0.635 0)
			(stroke
				(width 0.508)
				(type default)
			)
			(layer "F.SilkS")
		)
		(fp_rect
			(start -0.9652 1.778)
			(end 0.9652 -1.778)
			(stroke
				(width 0)
				(type default)
			)
			(fill no)
			(layer "F.CrtYd")
		)
		(fp_poly
			(pts
				(xy -0.9652 -1.778) (xy 0.9652 -1.778) (xy 0.9652 1.778) (xy -0.9652 1.778)
			)
			(stroke
				(width 0)
				(type default)
			)
			(fill no)
			(layer "F.Fab")
		)
		(pad "1" smd rect
			(at 0 -0.9652 270)
			(size 1.397 1.143)
			(layers "F.Cu" "F.Mask" "F.Paste")
			(net "P12V_HDD11")
		)
		(pad "2" smd rect
			(at 0 0.9652 270)
			(size 1.397 1.143)
			(layers "F.Cu" "F.Mask" "F.Paste")
			(net "GND")
		)
	)
	(footprint ""
		(layer "F.Cu")
		(at 243.713 -311.912 180)
		(property "Reference" "R1092"
			(at 0 0 180)
			(layer "F.SilkS")
			(hide yes)
			(effects
				(font
					(size 1.27 1.27)
				)
			)
		)
		(property "Value" "0R2J-2-GP"
			(at 0.064008 -3.993896 180)
			(unlocked yes)
			(layer "F.Fab")
			(hide yes)
			(effects
				(font
					(size 1.016 1.016)
					(thickness 0.1524)
				)
			)
		)
		(property "Device Type" "R402H16"
			(at 0.064008 -5.517896 180)
			(unlocked yes)
			(layer "F.Fab")
			(hide yes)
			(effects
				(font
					(size 1.016 1.016)
					(thickness 0.1524)
				)
			)
		)
		(duplicate_pad_numbers_are_jumpers no)
		(fp_line
			(start 0.508 -0.9398)
			(end -0.508 -0.9398)
			(stroke
				(width 0.1524)
				(type default)
			)
			(layer "F.SilkS")
		)
		(fp_line
			(start -0.508 -0.9398)
			(end -0.508 0.9398)
			(stroke
				(width 0.1524)
				(type default)
			)
			(layer "F.SilkS")
		)
		(fp_rect
			(start -0.508 0.9398)
			(end 0.508 -0.9398)
			(stroke
				(width 0)
				(type default)
			)
			(fill no)
			(layer "F.CrtYd")
		)
		(fp_rect
			(start -0.508 0.9398)
			(end 0.508 -0.9398)
			(stroke
				(width 0)
				(type default)
			)
			(fill no)
			(layer "F.Fab")
		)
		(pad "1" smd custom
			(at 0 -0.4445 180)
			(size 0.1397 0.1397)
			(layers "F.Cu" "F.Mask" "F.Paste")
			(net "MAX31790_A_ADD1")
			(options
				(clearance outline)
				(anchor circle)
			)
			(primitives
				(gr_poly
					(pts
						(arc
							(start -0.1778 -0.2794)
							(mid -0.249642 -0.249642)
							(end -0.2794 -0.1778)
						)
						(arc
							(start -0.2794 0.1778)
							(mid -0.249642 0.249642)
							(end -0.1778 0.2794)
						)
						(arc
							(start 0.1778 0.2794)
							(mid 0.249642 0.249642)
							(end 0.2794 0.1778)
						)
						(arc
							(start 0.2794 -0.1778)
							(mid 0.249642 -0.249642)
							(end 0.1778 -0.2794)
						)
					)
					(width 0)
					(fill yes)
				)
			)
		)
		(pad "2" smd custom
			(at 0 0.4445 180)
			(size 0.1397 0.1397)
			(layers "F.Cu" "F.Mask" "F.Paste")
			(net "GND")
			(options
				(clearance outline)
				(anchor circle)
			)
			(primitives
				(gr_poly
					(pts
						(arc
							(start -0.1778 -0.2794)
							(mid -0.249642 -0.249642)
							(end -0.2794 -0.1778)
						)
						(arc
							(start -0.2794 0.1778)
							(mid -0.249642 0.249642)
							(end -0.1778 0.2794)
						)
						(arc
							(start 0.1778 0.2794)
							(mid 0.249642 0.249642)
							(end 0.2794 0.1778)
						)
						(arc
							(start 0.2794 -0.1778)
							(mid 0.249642 -0.249642)
							(end 0.1778 -0.2794)
						)
					)
					(width 0)
					(fill yes)
				)
			)
		)
	)
)
